(kicad_pcb
	(version 20260206)
	(generator "pcbnew")
	(generator_version "10.0")
	(general
		(thickness 1.6)
		(legacy_teardrops no)
	)
	(paper "A4")
	(title_block
		(title "baseboard — 13948-1b.1110WZS1818.brd")
		(comment 1 "Honey Badger (Wiwynn) / footprints 42-49 of 2523")
	)
	(layers
		(0 "F.Cu" signal "TOP")
		(4 "In1.Cu" signal "L2GND")
		(6 "In2.Cu" signal "L3")
		(8 "In3.Cu" signal "L4VCC")
		(10 "In4.Cu" signal "L5VCC")
		(12 "In5.Cu" signal "L6")
		(14 "In6.Cu" signal "L7GND")
		(2 "B.Cu" signal "BOTTOM")
		(9 "F.Adhes" user "F.Adhesive")
		(11 "B.Adhes" user "B.Adhesive")
		(13 "F.Paste" user "Package Geometry/Pastemask Top")
		(15 "B.Paste" user "Package Geometry/Pastemask Bottom")
		(5 "F.SilkS" user "Ref Des/Silkscreen Top")
		(7 "B.SilkS" user "Ref Des/Silkscreen Bottom")
		(1 "F.Mask" user "Board Geometry/Soldermask Top")
		(3 "B.Mask" user "Board Geometry/Soldermask Bottom")
		(17 "Dwgs.User" user "User.Drawings")
		(19 "Cmts.User" user "User.Comments")
		(21 "Eco1.User" user "User.Eco1")
		(23 "Eco2.User" user "User.Eco2")
		(25 "Edge.Cuts" user "Board Geometry/Outline")
		(27 "Margin" user)
		(31 "F.CrtYd" user "Package Geometry/Place Bound Top")
		(29 "B.CrtYd" user "Package Geometry/Place Bound Bottom")
		(35 "F.Fab" user "Ref Des/Assembly Top")
		(33 "B.Fab" user "Ref Des/Assembly Bottom")
	)
	(footprint ""
		(layer "F.Cu")
		(at 269.748 -30.607 -90)
		(property "Reference" "PL5"
			(at 0 0 270)
			(layer "F.SilkS")
			(hide yes)
			(effects
				(font
					(size 1.27 1.27)
				)
			)
		)
		(property "Value" "IND-2D2UH-122-GP"
			(at -5.2451 -0.6604 270)
			(unlocked yes)
			(layer "F.Fab")
			(hide yes)
			(effects
				(font
					(size 1.016 1.016)
					(thickness 0.1524)
				)
			)
		)
		(property "Device Type" "L686647H119"
			(at -5.2451 -2.1844 270)
			(unlocked yes)
			(layer "F.Fab")
			(hide yes)
			(effects
				(font
					(size 1.016 1.016)
					(thickness 0.1524)
				)
			)
		)
		(duplicate_pad_numbers_are_jumpers no)
		(fp_line
			(start -4.318 3.4925)
			(end -4.318 -3.4925)
			(stroke
				(width 0.1524)
				(type default)
			)
			(layer "F.SilkS")
		)
		(fp_line
			(start 4.318 3.4925)
			(end -4.318 3.4925)
			(stroke
				(width 0.1524)
				(type default)
			)
			(layer "F.SilkS")
		)
		(fp_line
			(start -4.318 -3.4925)
			(end 4.318 -3.4925)
			(stroke
				(width 0.1524)
				(type default)
			)
			(layer "F.SilkS")
		)
		(fp_line
			(start 4.318 -3.4925)
			(end 4.318 3.4925)
			(stroke
				(width 0.1524)
				(type default)
			)
			(layer "F.SilkS")
		)
		(fp_rect
			(start -3.429 3.2385)
			(end 3.429 -3.2385)
			(stroke
				(width 0)
				(type default)
			)
			(fill no)
			(layer "F.CrtYd")
		)
		(fp_poly
			(pts
				(xy -4.3942 -3.7465) (xy 4.3942 -3.7465) (xy 4.3942 3.7465) (xy -4.3942 3.7465) (xy -4.3942 3.2385)
				(xy 3.429 3.2385) (xy 3.429 -3.2385) (xy -3.429 -3.2385) (xy -3.429 3.2258) (xy -4.3942 3.2258)
			)
			(stroke
				(width 0)
				(type default)
			)
			(fill no)
			(layer "F.CrtYd")
		)
		(fp_rect
			(start -4.3942 3.7465)
			(end 4.3942 -3.7465)
			(stroke
				(width 0)
				(type default)
			)
			(fill no)
			(layer "F.Fab")
		)
		(pad "1" smd rect
			(at -3.1115 0 270)
			(size 2.159 3.429)
			(drill
				(offset 0.127 0)
			)
			(layers "F.Cu" "F.Mask" "F.Paste")
			(net "P1V8_STBY_LL")
		)
		(pad "2" smd rect
			(at 3.1115 0 270)
			(size 2.159 3.429)
			(drill
				(offset -0.127 0)
			)
			(layers "F.Cu" "F.Mask" "F.Paste")
			(net "P1V8_STBY")
		)
	)
	(footprint ""
		(layer "F.Cu")
		(at 285.496 -163.703)
		(property "Reference" "TP133"
			(at 0 0 0)
			(layer "F.SilkS")
			(hide yes)
			(effects
				(font
					(size 1.27 1.27)
				)
			)
		)
		(property "Value" "TPAD28"
			(at 0.0127 -1.8034 0)
			(unlocked yes)
			(layer "F.Fab")
			(hide yes)
			(effects
				(font
					(size 1.016 1.016)
					(thickness 0.1524)
				)
			)
		)
		(property "Device Type" "TPAD28"
			(at 0.0127 -3.3274 0)
			(unlocked yes)
			(layer "F.Fab")
			(hide yes)
			(effects
				(font
					(size 1.016 1.016)
					(thickness 0.1524)
				)
			)
		)
		(duplicate_pad_numbers_are_jumpers no)
		(fp_poly
			(pts
				(arc
					(start 0.3556 0)
					(mid -0.3556 0)
					(end 0.3556 0)
				)
			)
			(stroke
				(width 0)
				(type default)
			)
			(fill no)
			(layer "F.CrtYd")
		)
		(fp_poly
			(pts
				(arc
					(start 0.6096 0)
					(mid -0.6096 0)
					(end 0.6096 0)
				)
			)
			(stroke
				(width 0)
				(type default)
			)
			(fill no)
			(layer "F.Fab")
		)
		(pad "1" smd circle
			(at 0 0)
			(size 0.7112 0.7112)
			(layers "F.Cu" "F.Mask" "F.Paste")
			(net "TP_BMC_GPIOF4")
		)
	)
	(footprint ""
		(layer "F.Cu")
		(at 316.401958 -64.77 90)
		(property "Reference" "R224"
			(at 0 0 90)
			(layer "F.SilkS")
			(hide yes)
			(effects
				(font
					(size 1.27 1.27)
				)
			)
		)
		(property "Value" "0R2J-2-GP"
			(at 0.064008 -3.993896 90)
			(unlocked yes)
			(layer "F.Fab")
			(hide yes)
			(effects
				(font
					(size 1.016 1.016)
					(thickness 0.1524)
				)
			)
		)
		(property "Device Type" "R402H16"
			(at 0.064008 -5.517896 90)
			(unlocked yes)
			(layer "F.Fab")
			(hide yes)
			(effects
				(font
					(size 1.016 1.016)
					(thickness 0.1524)
				)
			)
		)
		(duplicate_pad_numbers_are_jumpers no)
		(fp_line
			(start 0.508 -0.9398)
			(end -0.508 -0.9398)
			(stroke
				(width 0.1524)
				(type default)
			)
			(layer "F.SilkS")
		)
		(fp_line
			(start -0.508 -0.9398)
			(end -0.508 0.9398)
			(stroke
				(width 0.1524)
				(type default)
			)
			(layer "F.SilkS")
		)
		(fp_rect
			(start -0.508 0.9398)
			(end 0.508 -0.9398)
			(stroke
				(width 0)
				(type default)
			)
			(fill no)
			(layer "F.CrtYd")
		)
		(fp_rect
			(start -0.508 0.9398)
			(end 0.508 -0.9398)
			(stroke
				(width 0)
				(type default)
			)
			(fill no)
			(layer "F.Fab")
		)
		(pad "1" smd custom
			(at 0 -0.4445 90)
			(size 0.1397 0.1397)
			(layers "F.Cu" "F.Mask" "F.Paste")
			(net "NCSI_10G_RXD0_R")
			(options
				(clearance outline)
				(anchor circle)
			)
			(primitives
				(gr_poly
					(pts
						(arc
							(start -0.1778 -0.2794)
							(mid -0.249642 -0.249642)
							(end -0.2794 -0.1778)
						)
						(arc
							(start -0.2794 0.1778)
							(mid -0.249642 0.249642)
							(end -0.1778 0.2794)
						)
						(arc
							(start 0.1778 0.2794)
							(mid 0.249642 0.249642)
							(end 0.2794 0.1778)
						)
						(arc
							(start 0.2794 -0.1778)
							(mid 0.249642 -0.249642)
							(end 0.1778 -0.2794)
						)
					)
					(width 0)
					(fill yes)
				)
			)
		)
		(pad "2" smd custom
			(at 0 0.4445 90)
			(size 0.1397 0.1397)
			(layers "F.Cu" "F.Mask" "F.Paste")
			(net "NCSI_10G_RXD0")
			(options
				(clearance outline)
				(anchor circle)
			)
			(primitives
				(gr_poly
					(pts
						(arc
							(start -0.1778 -0.2794)
							(mid -0.249642 -0.249642)
							(end -0.2794 -0.1778)
						)
						(arc
							(start -0.2794 0.1778)
							(mid -0.249642 0.249642)
							(end -0.1778 0.2794)
						)
						(arc
							(start 0.1778 0.2794)
							(mid 0.249642 0.249642)
							(end 0.2794 0.1778)
						)
						(arc
							(start 0.2794 -0.1778)
							(mid 0.249642 -0.249642)
							(end 0.1778 -0.2794)
						)
					)
					(width 0)
					(fill yes)
				)
			)
		)
	)
	(footprint ""
		(layer "F.Cu")
		(at 337.566 -75.692 -90)
		(property "Reference" "R680"
			(at 0 0 270)
			(layer "F.SilkS")
			(hide yes)
			(effects
				(font
					(size 1.27 1.27)
				)
			)
		)
		(property "Value" "0R2J-2-GP"
			(at 0.064008 -3.993896 270)
			(unlocked yes)
			(layer "F.Fab")
			(hide yes)
			(effects
				(font
					(size 1.016 1.016)
					(thickness 0.1524)
				)
			)
		)
		(property "Device Type" "R402H16"
			(at 0.064008 -5.517896 270)
			(unlocked yes)
			(layer "F.Fab")
			(hide yes)
			(effects
				(font
					(size 1.016 1.016)
					(thickness 0.1524)
				)
			)
		)
		(duplicate_pad_numbers_are_jumpers no)
		(fp_line
			(start -0.508 -0.9398)
			(end -0.508 0.9398)
			(stroke
				(width 0.1524)
				(type default)
			)
			(layer "F.SilkS")
		)
		(fp_line
			(start 0.508 -0.9398)
			(end -0.508 -0.9398)
			(stroke
				(width 0.1524)
				(type default)
			)
			(layer "F.SilkS")
		)
		(fp_rect
			(start -0.508 0.9398)
			(end 0.508 -0.9398)
			(stroke
				(width 0)
				(type default)
			)
			(fill no)
			(layer "F.CrtYd")
		)
		(fp_rect
			(start -0.508 0.9398)
			(end 0.508 -0.9398)
			(stroke
				(width 0)
				(type default)
			)
			(fill no)
			(layer "F.Fab")
		)
		(pad "1" smd custom
			(at 0 -0.4445 270)
			(size 0.1397 0.1397)
			(layers "F.Cu" "F.Mask" "F.Paste")
			(net "ROMD1_R")
			(options
				(clearance outline)
				(anchor circle)
			)
			(primitives
				(gr_poly
					(pts
						(arc
							(start -0.1778 -0.2794)
							(mid -0.249642 -0.249642)
							(end -0.2794 -0.1778)
						)
						(arc
							(start -0.2794 0.1778)
							(mid -0.249642 0.249642)
							(end -0.1778 0.2794)
						)
						(arc
							(start 0.1778 0.2794)
							(mid 0.249642 0.249642)
							(end 0.2794 0.1778)
						)
						(arc
							(start 0.2794 -0.1778)
							(mid 0.249642 -0.249642)
							(end 0.1778 -0.2794)
						)
					)
					(width 0)
					(fill yes)
				)
			)
		)
		(pad "2" smd custom
			(at 0 0.4445 270)
			(size 0.1397 0.1397)
			(layers "F.Cu" "F.Mask" "F.Paste")
			(net "ROMD1_R_R")
			(options
				(clearance outline)
				(anchor circle)
			)
			(primitives
				(gr_poly
					(pts
						(arc
							(start -0.1778 -0.2794)
							(mid -0.249642 -0.249642)
							(end -0.2794 -0.1778)
						)
						(arc
							(start -0.2794 0.1778)
							(mid -0.249642 0.249642)
							(end -0.1778 0.2794)
						)
						(arc
							(start 0.1778 0.2794)
							(mid 0.249642 0.249642)
							(end 0.2794 0.1778)
						)
						(arc
							(start 0.2794 -0.1778)
							(mid 0.249642 -0.249642)
							(end 0.1778 -0.2794)
						)
					)
					(width 0)
					(fill yes)
				)
			)
		)
	)
	(footprint ""
		(layer "F.Cu")
		(at 90.5002 -3.683)
		(property "Reference" "PC197"
			(at 0 0 0)
			(layer "F.SilkS")
			(hide yes)
			(effects
				(font
					(size 1.27 1.27)
				)
			)
		)
		(property "Value" "SC22U6D3V6KX-2-GP"
			(at -0.0762 -5.1308 0)
			(unlocked yes)
			(layer "F.Fab")
			(hide yes)
			(effects
				(font
					(size 1.016 1.016)
					(thickness 0.1524)
				)
			)
		)
		(property "Device Type" "C1206H71"
			(at -0.127 -6.6548 0)
			(unlocked yes)
			(layer "F.Fab")
			(hide yes)
			(effects
				(font
					(size 1.016 1.016)
					(thickness 0.1524)
				)
			)
		)
		(duplicate_pad_numbers_are_jumpers no)
		(fp_line
			(start -1.016 -2.2352)
			(end 1.016 -2.2352)
			(stroke
				(width 0.1524)
				(type default)
			)
			(layer "F.SilkS")
		)
		(fp_line
			(start -1.016 -0.8382)
			(end -1.016 -2.2352)
			(stroke
				(width 0.1524)
				(type default)
			)
			(layer "F.SilkS")
		)
		(fp_line
			(start -1.016 2.2352)
			(end -1.016 0.8382)
			(stroke
				(width 0.1524)
				(type default)
			)
			(layer "F.SilkS")
		)
		(fp_line
			(start 1.016 -2.2352)
			(end 1.016 -0.8382)
			(stroke
				(width 0.1524)
				(type default)
			)
			(layer "F.SilkS")
		)
		(fp_line
			(start 1.016 0.8382)
			(end 1.016 2.2352)
			(stroke
				(width 0.1524)
				(type default)
			)
			(layer "F.SilkS")
		)
		(fp_line
			(start 1.016 2.2352)
			(end -1.016 2.2352)
			(stroke
				(width 0.1524)
				(type default)
			)
			(layer "F.SilkS")
		)
		(fp_rect
			(start -1.0922 2.3114)
			(end 1.0922 -2.3114)
			(stroke
				(width 0)
				(type default)
			)
			(fill no)
			(layer "F.CrtYd")
		)
		(fp_poly
			(pts
				(xy 1.0922 -2.3114) (xy 1.0922 2.3114) (xy -1.0922 2.3114) (xy -1.0922 -2.3114)
			)
			(stroke
				(width 0)
				(type default)
			)
			(fill no)
			(layer "F.Fab")
		)
		(pad "1" smd rect
			(at 0 -1.397)
			(size 1.651 1.27)
			(layers "F.Cu" "F.Mask" "F.Paste")
			(net "P0V955_C")
		)
		(pad "2" smd rect
			(at 0 1.397)
			(size 1.651 1.27)
			(layers "F.Cu" "F.Mask" "F.Paste")
			(net "GND")
		)
	)
	(footprint ""
		(layer "F.Cu")
		(at 95.89897 -83.947 90)
		(property "Reference" "SR797"
			(at 0 0 90)
			(layer "F.SilkS")
			(hide yes)
			(effects
				(font
					(size 1.27 1.27)
				)
			)
		)
		(property "Value" "4K75R2F-1-GP"
			(at 0.064008 -3.993896 90)
			(unlocked yes)
			(layer "F.Fab")
			(hide yes)
			(effects
				(font
					(size 1.016 1.016)
					(thickness 0.1524)
				)
			)
		)
		(property "Device Type" "R402H16"
			(at 0.064008 -5.517896 90)
			(unlocked yes)
			(layer "F.Fab")
			(hide yes)
			(effects
				(font
					(size 1.016 1.016)
					(thickness 0.1524)
				)
			)
		)
		(duplicate_pad_numbers_are_jumpers no)
		(fp_line
			(start 0.508 -0.9398)
			(end -0.508 -0.9398)
			(stroke
				(width 0.1524)
				(type default)
			)
			(layer "F.SilkS")
		)
		(fp_line
			(start -0.508 -0.9398)
			(end -0.508 0.9398)
			(stroke
				(width 0.1524)
				(type default)
			)
			(layer "F.SilkS")
		)
		(fp_rect
			(start -0.508 0.9398)
			(end 0.508 -0.9398)
			(stroke
				(width 0)
				(type default)
			)
			(fill no)
			(layer "F.CrtYd")
		)
		(fp_rect
			(start -0.508 0.9398)
			(end 0.508 -0.9398)
			(stroke
				(width 0)
				(type default)
			)
			(fill no)
			(layer "F.Fab")
		)
		(pad "1" smd custom
			(at 0 -0.4445 90)
			(size 0.1397 0.1397)
			(layers "F.Cu" "F.Mask" "F.Paste")
			(net "P1V8_E")
			(options
				(clearance outline)
				(anchor circle)
			)
			(primitives
				(gr_poly
					(pts
						(arc
							(start -0.1778 -0.2794)
							(mid -0.249642 -0.249642)
							(end -0.2794 -0.1778)
						)
						(arc
							(start -0.2794 0.1778)
							(mid -0.249642 0.249642)
							(end -0.1778 0.2794)
						)
						(arc
							(start 0.1778 0.2794)
							(mid 0.249642 0.249642)
							(end 0.2794 0.1778)
						)
						(arc
							(start 0.2794 -0.1778)
							(mid 0.249642 -0.249642)
							(end 0.1778 -0.2794)
						)
					)
					(width 0)
					(fill yes)
				)
			)
		)
		(pad "2" smd custom
			(at 0 0.4445 90)
			(size 0.1397 0.1397)
			(layers "F.Cu" "F.Mask" "F.Paste")
			(net "EXP_CLK_SEL1")
			(options
				(clearance outline)
				(anchor circle)
			)
			(primitives
				(gr_poly
					(pts
						(arc
							(start -0.1778 -0.2794)
							(mid -0.249642 -0.249642)
							(end -0.2794 -0.1778)
						)
						(arc
							(start -0.2794 0.1778)
							(mid -0.249642 0.249642)
							(end -0.1778 0.2794)
						)
						(arc
							(start 0.1778 0.2794)
							(mid 0.249642 0.249642)
							(end 0.2794 0.1778)
						)
						(arc
							(start 0.2794 -0.1778)
							(mid 0.249642 -0.249642)
							(end 0.1778 -0.2794)
						)
					)
					(width 0)
					(fill yes)
				)
			)
		)
	)
	(footprint ""
		(layer "F.Cu")
		(at 340.516718 -157.330648 -90)
		(property "Reference" "R228"
			(at 0 0 270)
			(layer "F.SilkS")
			(hide yes)
			(effects
				(font
					(size 1.27 1.27)
				)
			)
		)
		(property "Value" "4K7R2F-GP"
			(at 0.064008 -3.993896 270)
			(unlocked yes)
			(layer "F.Fab")
			(hide yes)
			(effects
				(font
					(size 1.016 1.016)
					(thickness 0.1524)
				)
			)
		)
		(property "Device Type" "R402H16"
			(at 0.064008 -5.517896 270)
			(unlocked yes)
			(layer "F.Fab")
			(hide yes)
			(effects
				(font
					(size 1.016 1.016)
					(thickness 0.1524)
				)
			)
		)
		(duplicate_pad_numbers_are_jumpers no)
		(fp_line
			(start -0.508 -0.9398)
			(end -0.508 0.9398)
			(stroke
				(width 0.1524)
				(type default)
			)
			(layer "F.SilkS")
		)
		(fp_line
			(start 0.508 -0.9398)
			(end -0.508 -0.9398)
			(stroke
				(width 0.1524)
				(type default)
			)
			(layer "F.SilkS")
		)
		(fp_rect
			(start -0.508 0.9398)
			(end 0.508 -0.9398)
			(stroke
				(width 0)
				(type default)
			)
			(fill no)
			(layer "F.CrtYd")
		)
		(fp_rect
			(start -0.508 0.9398)
			(end 0.508 -0.9398)
			(stroke
				(width 0)
				(type default)
			)
			(fill no)
			(layer "F.Fab")
		)
		(pad "1" smd custom
			(at 0 -0.4445 270)
			(size 0.1397 0.1397)
			(layers "F.Cu" "F.Mask" "F.Paste")
			(net "P3V3_STBY")
			(options
				(clearance outline)
				(anchor circle)
			)
			(primitives
				(gr_poly
					(pts
						(arc
							(start -0.1778 -0.2794)
							(mid -0.249642 -0.249642)
							(end -0.2794 -0.1778)
						)
						(arc
							(start -0.2794 0.1778)
							(mid -0.249642 0.249642)
							(end -0.1778 0.2794)
						)
						(arc
							(start 0.1778 0.2794)
							(mid 0.249642 0.249642)
							(end 0.2794 0.1778)
						)
						(arc
							(start 0.2794 -0.1778)
							(mid 0.249642 -0.249642)
							(end 0.1778 -0.2794)
						)
					)
					(width 0)
					(fill yes)
				)
			)
		)
		(pad "2" smd custom
			(at 0 0.4445 270)
			(size 0.1397 0.1397)
			(layers "F.Cu" "F.Mask" "F.Paste")
			(net "USB_EN_2")
			(options
				(clearance outline)
				(anchor circle)
			)
			(primitives
				(gr_poly
					(pts
						(arc
							(start -0.1778 -0.2794)
							(mid -0.249642 -0.249642)
							(end -0.2794 -0.1778)
						)
						(arc
							(start -0.2794 0.1778)
							(mid -0.249642 0.249642)
							(end -0.1778 0.2794)
						)
						(arc
							(start 0.1778 0.2794)
							(mid 0.249642 0.249642)
							(end 0.2794 0.1778)
						)
						(arc
							(start 0.2794 -0.1778)
							(mid 0.249642 -0.249642)
							(end 0.1778 -0.2794)
						)
					)
					(width 0)
					(fill yes)
				)
			)
		)
	)
	(footprint ""
		(layer "F.Cu")
		(at 48.14697 -144.399)
		(property "Reference" "SR791"
			(at 0 0 0)
			(layer "F.SilkS")
			(hide yes)
			(effects
				(font
					(size 1.27 1.27)
				)
			)
		)
		(property "Value" "4K7R2F-GP"
			(at 0.064008 -3.993896 0)
			(unlocked yes)
			(layer "F.Fab")
			(hide yes)
			(effects
				(font
					(size 1.016 1.016)
					(thickness 0.1524)
				)
			)
		)
		(property "Device Type" "R402H16"
			(at 0.064008 -5.517896 0)
			(unlocked yes)
			(layer "F.Fab")
			(hide yes)
			(effects
				(font
					(size 1.016 1.016)
					(thickness 0.1524)
				)
			)
		)
		(duplicate_pad_numbers_are_jumpers no)
		(fp_line
			(start -0.508 -0.9398)
			(end -0.508 0.9398)
			(stroke
				(width 0.1524)
				(type default)
			)
			(layer "F.SilkS")
		)
		(fp_line
			(start 0.508 -0.9398)
			(end -0.508 -0.9398)
			(stroke
				(width 0.1524)
				(type default)
			)
			(layer "F.SilkS")
		)
		(fp_rect
			(start -0.508 0.9398)
			(end 0.508 -0.9398)
			(stroke
				(width 0)
				(type default)
			)
			(fill no)
			(layer "F.CrtYd")
		)
		(fp_rect
			(start -0.508 0.9398)
			(end 0.508 -0.9398)
			(stroke
				(width 0)
				(type default)
			)
			(fill no)
			(layer "F.Fab")
		)
		(pad "1" smd custom
			(at 0 -0.4445)
			(size 0.1397 0.1397)
			(layers "F.Cu" "F.Mask" "F.Paste")
			(net "P1V8_E")
			(options
				(clearance outline)
				(anchor circle)
			)
			(primitives
				(gr_poly
					(pts
						(arc
							(start -0.1778 -0.2794)
							(mid -0.249642 -0.249642)
							(end -0.2794 -0.1778)
						)
						(arc
							(start -0.2794 0.1778)
							(mid -0.249642 0.249642)
							(end -0.1778 0.2794)
						)
						(arc
							(start 0.1778 0.2794)
							(mid 0.249642 0.249642)
							(end 0.2794 0.1778)
						)
						(arc
							(start 0.2794 -0.1778)
							(mid 0.249642 -0.249642)
							(end 0.1778 -0.2794)
						)
					)
					(width 0)
					(fill yes)
				)
			)
		)
		(pad "2" smd custom
			(at 0 0.4445)
			(size 0.1397 0.1397)
			(layers "F.Cu" "F.Mask" "F.Paste")
			(net "EXP_RESET_N")
			(options
				(clearance outline)
				(anchor circle)
			)
			(primitives
				(gr_poly
					(pts
						(arc
							(start -0.1778 -0.2794)
							(mid -0.249642 -0.249642)
							(end -0.2794 -0.1778)
						)
						(arc
							(start -0.2794 0.1778)
							(mid -0.249642 0.249642)
							(end -0.1778 0.2794)
						)
						(arc
							(start 0.1778 0.2794)
							(mid 0.249642 0.249642)
							(end 0.2794 0.1778)
						)
						(arc
							(start 0.2794 -0.1778)
							(mid 0.249642 -0.249642)
							(end 0.1778 -0.2794)
						)
					)
					(width 0)
					(fill yes)
				)
			)
		)
	)
)
